(kicad_pcb
	(version 20260206)
	(generator "pcbnew")
	(generator_version "10.0")
	(general
		(thickness 1.6)
		(legacy_teardrops no)
	)
	(paper "A4")
	(title_block
		(title "dpb — 14545-sa.0730WZS0815.brd")
		(comment 1 "Honey Badger (Wiwynn) / footprints 364-370 of 1066")
	)
	(layers
		(0 "F.Cu" signal "TOP")
		(4 "In1.Cu" signal "L2GND")
		(6 "In2.Cu" signal "L3")
		(8 "In3.Cu" signal "L4VCC")
		(10 "In4.Cu" signal "L5VCC")
		(12 "In5.Cu" signal "L6")
		(14 "In6.Cu" signal "L7GND")
		(2 "B.Cu" signal "BOTTOM")
		(9 "F.Adhes" user "F.Adhesive")
		(11 "B.Adhes" user "B.Adhesive")
		(13 "F.Paste" user "Package Geometry/Pastemask Top")
		(15 "B.Paste" user "Package Geometry/Pastemask Bottom")
		(5 "F.SilkS" user "Ref Des/Silkscreen Top")
		(7 "B.SilkS" user "Ref Des/Silkscreen Bottom")
		(1 "F.Mask" user "Board Geometry/Soldermask Top")
		(3 "B.Mask" user "Board Geometry/Soldermask Bottom")
		(17 "Dwgs.User" user "User.Drawings")
		(19 "Cmts.User" user "User.Comments")
		(21 "Eco1.User" user "User.Eco1")
		(23 "Eco2.User" user "User.Eco2")
		(25 "Edge.Cuts" user "Board Geometry/Outline")
		(27 "Margin" user)
		(31 "F.CrtYd" user "Package Geometry/Place Bound Top")
		(29 "B.CrtYd" user "Package Geometry/Place Bound Bottom")
		(35 "F.Fab" user "Ref Des/Assembly Top")
		(33 "B.Fab" user "Ref Des/Assembly Bottom")
	)
	(footprint ""
		(layer "F.Cu")
		(at 199.820784 -190.470028 -90)
		(property "Reference" "U11"
			(at 0 0 270)
			(layer "F.SilkS")
			(hide yes)
			(effects
				(font
					(size 1.27 1.27)
				)
			)
		)
		(property "Value" "P2003EVG-GP"
			(at 0 -11.1252 270)
			(unlocked yes)
			(layer "F.Fab")
			(hide yes)
			(effects
				(font
					(size 1.016 1.016)
					(thickness 0.1524)
				)
			)
		)
		(property "Device Type" "SOIC8H79"
			(at 0 -12.6492 270)
			(unlocked yes)
			(layer "F.Fab")
			(hide yes)
			(effects
				(font
					(size 1.016 1.016)
					(thickness 0.1524)
				)
			)
		)
		(duplicate_pad_numbers_are_jumpers no)
		(fp_line
			(start -2.6162 3.429)
			(end -2.6162 1.4732)
			(stroke
				(width 0.4064)
				(type default)
			)
			(layer "F.SilkS")
		)
		(fp_line
			(start -2.7432 1.4224)
			(end 2.1336 1.4224)
			(stroke
				(width 0.1524)
				(type default)
			)
			(layer "F.SilkS")
		)
		(fp_line
			(start 2.1336 1.4224)
			(end 2.1336 -1.4224)
			(stroke
				(width 0.1524)
				(type default)
			)
			(layer "F.SilkS")
		)
		(fp_line
			(start -2.2352 0)
			(end -2.7432 0.508)
			(stroke
				(width 0.1524)
				(type default)
			)
			(layer "F.SilkS")
		)
		(fp_line
			(start -2.7432 -0.508)
			(end -2.2352 0)
			(stroke
				(width 0.1524)
				(type default)
			)
			(layer "F.SilkS")
		)
		(fp_line
			(start -2.7432 -1.4224)
			(end -2.7432 1.4224)
			(stroke
				(width 0.1524)
				(type default)
			)
			(layer "F.SilkS")
		)
		(fp_line
			(start 2.1336 -1.4224)
			(end -2.7432 -1.4224)
			(stroke
				(width 0.1524)
				(type default)
			)
			(layer "F.SilkS")
		)
		(fp_poly
			(pts
				(xy 2.2098 -1.4224) (xy 2.2098 1.4224) (xy -2.2225 1.4224) (xy -2.2225 -1.4224)
			)
			(stroke
				(width 0)
				(type default)
			)
			(fill yes)
			(layer "F.SilkS")
		)
		(fp_rect
			(start -2.4511 2.9972)
			(end 2.4511 -2.9972)
			(stroke
				(width 0)
				(type default)
			)
			(fill no)
			(layer "F.CrtYd")
		)
		(fp_poly
			(pts
				(xy -2.8194 3.6322) (xy -2.8194 -3.6322) (xy 2.8194 -3.6322) (xy 2.8194 -2.2987) (xy 2.4511 -2.2987)
				(xy 2.4511 -2.9972) (xy -2.4511 -2.9972) (xy -2.4511 2.9972) (xy 2.4511 2.9972) (xy 2.4511 -2.286)
				(xy 2.8194 -2.286) (xy 2.8194 3.6322)
			)
			(stroke
				(width 0)
				(type default)
			)
			(fill no)
			(layer "F.CrtYd")
		)
		(fp_rect
			(start -2.8194 3.6322)
			(end 2.8194 -3.6322)
			(stroke
				(width 0)
				(type default)
			)
			(fill no)
			(layer "F.Fab")
		)
		(pad "1" smd rect
			(at -1.905 2.54 270)
			(size 0.635 1.651)
			(layers "F.Cu" "F.Mask" "F.Paste")
			(net "P12V")
		)
		(pad "2" smd rect
			(at -0.635 2.54 270)
			(size 0.635 1.651)
			(layers "F.Cu" "F.Mask" "F.Paste")
			(net "P12V")
		)
		(pad "3" smd rect
			(at 0.635 2.54 270)
			(size 0.635 1.651)
			(layers "F.Cu" "F.Mask" "F.Paste")
			(net "P12V")
		)
		(pad "4" smd rect
			(at 1.905 2.54 270)
			(size 0.635 1.651)
			(layers "F.Cu" "F.Mask" "F.Paste")
			(net "SW_HDD3_N")
		)
		(pad "5" smd rect
			(at 1.905 -2.54 270)
			(size 0.635 1.651)
			(layers "F.Cu" "F.Mask" "F.Paste")
			(net "P12V_HDD3")
		)
		(pad "6" smd rect
			(at 0.635 -2.54 270)
			(size 0.635 1.651)
			(layers "F.Cu" "F.Mask" "F.Paste")
			(net "P12V_HDD3")
		)
		(pad "7" smd rect
			(at -0.635 -2.54 270)
			(size 0.635 1.651)
			(layers "F.Cu" "F.Mask" "F.Paste")
			(net "P12V_HDD3")
		)
		(pad "8" smd rect
			(at -1.905 -2.54 270)
			(size 0.635 1.651)
			(layers "F.Cu" "F.Mask" "F.Paste")
			(net "P12V_HDD3")
		)
	)
	(footprint ""
		(layer "F.Cu")
		(at 217.8812 -497.713 180)
		(property "Reference" "C114"
			(at 0 0 180)
			(layer "F.SilkS")
			(hide yes)
			(effects
				(font
					(size 1.27 1.27)
				)
			)
		)
		(property "Value" "SC10U25V6KX-1GP"
			(at -0.0762 -5.1308 180)
			(unlocked yes)
			(layer "F.Fab")
			(hide yes)
			(effects
				(font
					(size 1.016 1.016)
					(thickness 0.1524)
				)
			)
		)
		(property "Device Type" "C1206H71"
			(at -0.127 -6.6548 180)
			(unlocked yes)
			(layer "F.Fab")
			(hide yes)
			(effects
				(font
					(size 1.016 1.016)
					(thickness 0.1524)
				)
			)
		)
		(duplicate_pad_numbers_are_jumpers no)
		(fp_line
			(start 1.016 2.2352)
			(end -1.016 2.2352)
			(stroke
				(width 0.1524)
				(type default)
			)
			(layer "F.SilkS")
		)
		(fp_line
			(start 1.016 0.8382)
			(end 1.016 2.2352)
			(stroke
				(width 0.1524)
				(type default)
			)
			(layer "F.SilkS")
		)
		(fp_line
			(start 1.016 -2.2352)
			(end 1.016 -0.8382)
			(stroke
				(width 0.1524)
				(type default)
			)
			(layer "F.SilkS")
		)
		(fp_line
			(start -1.016 2.2352)
			(end -1.016 0.8382)
			(stroke
				(width 0.1524)
				(type default)
			)
			(layer "F.SilkS")
		)
		(fp_line
			(start -1.016 -0.8382)
			(end -1.016 -2.2352)
			(stroke
				(width 0.1524)
				(type default)
			)
			(layer "F.SilkS")
		)
		(fp_line
			(start -1.016 -2.2352)
			(end 1.016 -2.2352)
			(stroke
				(width 0.1524)
				(type default)
			)
			(layer "F.SilkS")
		)
		(fp_rect
			(start -1.0922 2.3114)
			(end 1.0922 -2.3114)
			(stroke
				(width 0)
				(type default)
			)
			(fill no)
			(layer "F.CrtYd")
		)
		(fp_poly
			(pts
				(xy 1.0922 -2.3114) (xy 1.0922 2.3114) (xy -1.0922 2.3114) (xy -1.0922 -2.3114)
			)
			(stroke
				(width 0)
				(type default)
			)
			(fill no)
			(layer "F.Fab")
		)
		(pad "1" smd rect
			(at 0 -1.397 180)
			(size 1.651 1.27)
			(layers "F.Cu" "F.Mask" "F.Paste")
			(net "P12V_HDD0")
		)
		(pad "2" smd rect
			(at 0 1.397 180)
			(size 1.651 1.27)
			(layers "F.Cu" "F.Mask" "F.Paste")
			(net "GND")
		)
	)
	(footprint ""
		(layer "F.Cu")
		(at 191.092582 -286.103568 -90)
		(property "Reference" "R135"
			(at 0 0 270)
			(layer "F.SilkS")
			(hide yes)
			(effects
				(font
					(size 1.27 1.27)
				)
			)
		)
		(property "Value" "1KR2F-3-GP"
			(at 0.064008 -3.993896 270)
			(unlocked yes)
			(layer "F.Fab")
			(hide yes)
			(effects
				(font
					(size 1.016 1.016)
					(thickness 0.1524)
				)
			)
		)
		(property "Device Type" "R402H16"
			(at 0.064008 -5.517896 270)
			(unlocked yes)
			(layer "F.Fab")
			(hide yes)
			(effects
				(font
					(size 1.016 1.016)
					(thickness 0.1524)
				)
			)
		)
		(duplicate_pad_numbers_are_jumpers no)
		(fp_line
			(start -0.508 -0.9398)
			(end -0.508 0.9398)
			(stroke
				(width 0.1524)
				(type default)
			)
			(layer "F.SilkS")
		)
		(fp_line
			(start 0.508 -0.9398)
			(end -0.508 -0.9398)
			(stroke
				(width 0.1524)
				(type default)
			)
			(layer "F.SilkS")
		)
		(fp_rect
			(start -0.508 0.9398)
			(end 0.508 -0.9398)
			(stroke
				(width 0)
				(type default)
			)
			(fill no)
			(layer "F.CrtYd")
		)
		(fp_rect
			(start -0.508 0.9398)
			(end 0.508 -0.9398)
			(stroke
				(width 0)
				(type default)
			)
			(fill no)
			(layer "F.Fab")
		)
		(pad "1" smd custom
			(at 0 -0.4445 270)
			(size 0.1397 0.1397)
			(layers "F.Cu" "F.Mask" "F.Paste")
			(net "P3V3")
			(options
				(clearance outline)
				(anchor circle)
			)
			(primitives
				(gr_poly
					(pts
						(arc
							(start -0.1778 -0.2794)
							(mid -0.249642 -0.249642)
							(end -0.2794 -0.1778)
						)
						(arc
							(start -0.2794 0.1778)
							(mid -0.249642 0.249642)
							(end -0.1778 0.2794)
						)
						(arc
							(start 0.1778 0.2794)
							(mid 0.249642 0.249642)
							(end 0.2794 0.1778)
						)
						(arc
							(start 0.2794 -0.1778)
							(mid 0.249642 -0.249642)
							(end 0.1778 -0.2794)
						)
					)
					(width 0)
					(fill yes)
				)
			)
		)
		(pad "2" smd custom
			(at 0 0.4445 270)
			(size 0.1397 0.1397)
			(layers "F.Cu" "F.Mask" "F.Paste")
			(net "SW_PWR_HDD2")
			(options
				(clearance outline)
				(anchor circle)
			)
			(primitives
				(gr_poly
					(pts
						(arc
							(start -0.1778 -0.2794)
							(mid -0.249642 -0.249642)
							(end -0.2794 -0.1778)
						)
						(arc
							(start -0.2794 0.1778)
							(mid -0.249642 0.249642)
							(end -0.1778 0.2794)
						)
						(arc
							(start 0.1778 0.2794)
							(mid 0.249642 0.249642)
							(end 0.2794 0.1778)
						)
						(arc
							(start 0.2794 -0.1778)
							(mid 0.249642 -0.249642)
							(end 0.1778 -0.2794)
						)
					)
					(width 0)
					(fill yes)
				)
			)
		)
	)
	(footprint ""
		(layer "F.Cu")
		(at 78.358746 -91.4527 90)
		(property "Reference" "R232"
			(at 0 0 90)
			(layer "F.SilkS")
			(hide yes)
			(effects
				(font
					(size 1.27 1.27)
				)
			)
		)
		(property "Value" "4K7R2J-2-GP"
			(at 0.064008 -3.993896 90)
			(unlocked yes)
			(layer "F.Fab")
			(hide yes)
			(effects
				(font
					(size 1.016 1.016)
					(thickness 0.1524)
				)
			)
		)
		(property "Device Type" "R402H16"
			(at 0.064008 -5.517896 90)
			(unlocked yes)
			(layer "F.Fab")
			(hide yes)
			(effects
				(font
					(size 1.016 1.016)
					(thickness 0.1524)
				)
			)
		)
		(duplicate_pad_numbers_are_jumpers no)
		(fp_line
			(start 0.508 -0.9398)
			(end -0.508 -0.9398)
			(stroke
				(width 0.1524)
				(type default)
			)
			(layer "F.SilkS")
		)
		(fp_line
			(start -0.508 -0.9398)
			(end -0.508 0.9398)
			(stroke
				(width 0.1524)
				(type default)
			)
			(layer "F.SilkS")
		)
		(fp_rect
			(start -0.508 0.9398)
			(end 0.508 -0.9398)
			(stroke
				(width 0)
				(type default)
			)
			(fill no)
			(layer "F.CrtYd")
		)
		(fp_rect
			(start -0.508 0.9398)
			(end 0.508 -0.9398)
			(stroke
				(width 0)
				(type default)
			)
			(fill no)
			(layer "F.Fab")
		)
		(pad "1" smd custom
			(at 0 -0.4445 90)
			(size 0.1397 0.1397)
			(layers "F.Cu" "F.Mask" "F.Paste")
			(net "P12V")
			(options
				(clearance outline)
				(anchor circle)
			)
			(primitives
				(gr_poly
					(pts
						(arc
							(start -0.1778 -0.2794)
							(mid -0.249642 -0.249642)
							(end -0.2794 -0.1778)
						)
						(arc
							(start -0.2794 0.1778)
							(mid -0.249642 0.249642)
							(end -0.1778 0.2794)
						)
						(arc
							(start 0.1778 0.2794)
							(mid 0.249642 0.249642)
							(end 0.2794 0.1778)
						)
						(arc
							(start 0.2794 -0.1778)
							(mid 0.249642 -0.249642)
							(end 0.1778 -0.2794)
						)
					)
					(width 0)
					(fill yes)
				)
			)
		)
		(pad "2" smd custom
			(at 0 0.4445 90)
			(size 0.1397 0.1397)
			(layers "F.Cu" "F.Mask" "F.Paste")
			(net "SW_HDD9_R")
			(options
				(clearance outline)
				(anchor circle)
			)
			(primitives
				(gr_poly
					(pts
						(arc
							(start -0.1778 -0.2794)
							(mid -0.249642 -0.249642)
							(end -0.2794 -0.1778)
						)
						(arc
							(start -0.2794 0.1778)
							(mid -0.249642 0.249642)
							(end -0.1778 0.2794)
						)
						(arc
							(start 0.1778 0.2794)
							(mid 0.249642 0.249642)
							(end 0.2794 0.1778)
						)
						(arc
							(start 0.2794 -0.1778)
							(mid 0.249642 -0.249642)
							(end 0.1778 -0.2794)
						)
					)
					(width 0)
					(fill yes)
				)
			)
		)
	)
	(footprint ""
		(layer "F.Cu")
		(at 232.409746 -26.1747)
		(property "Reference" "TP22"
			(at 0 0 0)
			(layer "F.SilkS")
			(hide yes)
			(effects
				(font
					(size 1.27 1.27)
				)
			)
		)
		(property "Value" "TPAD32-GP"
			(at 0 -3.166364 0)
			(unlocked yes)
			(layer "F.Fab")
			(hide yes)
			(effects
				(font
					(size 1.016 1.016)
					(thickness 0.1524)
				)
			)
		)
		(property "Device Type" "TPAD32"
			(at 0 -4.690618 0)
			(unlocked yes)
			(layer "F.Fab")
			(hide yes)
			(effects
				(font
					(size 1.016 1.016)
					(thickness 0.1524)
				)
			)
		)
		(duplicate_pad_numbers_are_jumpers no)
		(fp_poly
			(pts
				(arc
					(start 0.4064 0)
					(mid -0.4064 0)
					(end 0.4064 0)
				)
			)
			(stroke
				(width 0)
				(type default)
			)
			(fill no)
			(layer "F.CrtYd")
		)
		(fp_poly
			(pts
				(arc
					(start 0.7112 0)
					(mid -0.7112 0)
					(end 0.7112 0)
				)
			)
			(stroke
				(width 0)
				(type default)
			)
			(fill no)
			(layer "F.Fab")
		)
		(pad "1" smd circle
			(at 0 0)
			(size 0.8128 0.8128)
			(layers "F.Cu" "F.Mask" "F.Paste")
			(net "P5VA_PGD")
		)
	)
	(footprint ""
		(layer "F.Cu")
		(at 195.961 -86.233 180)
		(property "Reference" "R412"
			(at 0 0 180)
			(layer "F.SilkS")
			(hide yes)
			(effects
				(font
					(size 1.27 1.27)
				)
			)
		)
		(property "Value" "0R2J-2-GP"
			(at 0.064008 -3.993896 180)
			(unlocked yes)
			(layer "F.Fab")
			(hide yes)
			(effects
				(font
					(size 1.016 1.016)
					(thickness 0.1524)
				)
			)
		)
		(property "Device Type" "R402H16"
			(at 0.064008 -5.517896 180)
			(unlocked yes)
			(layer "F.Fab")
			(hide yes)
			(effects
				(font
					(size 1.016 1.016)
					(thickness 0.1524)
				)
			)
		)
		(duplicate_pad_numbers_are_jumpers no)
		(fp_line
			(start 0.508 -0.9398)
			(end -0.508 -0.9398)
			(stroke
				(width 0.1524)
				(type default)
			)
			(layer "F.SilkS")
		)
		(fp_line
			(start -0.508 -0.9398)
			(end -0.508 0.9398)
			(stroke
				(width 0.1524)
				(type default)
			)
			(layer "F.SilkS")
		)
		(fp_rect
			(start -0.508 0.9398)
			(end 0.508 -0.9398)
			(stroke
				(width 0)
				(type default)
			)
			(fill no)
			(layer "F.CrtYd")
		)
		(fp_rect
			(start -0.508 0.9398)
			(end 0.508 -0.9398)
			(stroke
				(width 0)
				(type default)
			)
			(fill no)
			(layer "F.Fab")
		)
		(pad "1" smd custom
			(at 0 -0.4445 180)
			(size 0.1397 0.1397)
			(layers "F.Cu" "F.Mask" "F.Paste")
			(net "SW_HDD4_G")
			(options
				(clearance outline)
				(anchor circle)
			)
			(primitives
				(gr_poly
					(pts
						(arc
							(start -0.1778 -0.2794)
							(mid -0.249642 -0.249642)
							(end -0.2794 -0.1778)
						)
						(arc
							(start -0.2794 0.1778)
							(mid -0.249642 0.249642)
							(end -0.1778 0.2794)
						)
						(arc
							(start 0.1778 0.2794)
							(mid 0.249642 0.249642)
							(end 0.2794 0.1778)
						)
						(arc
							(start 0.2794 -0.1778)
							(mid 0.249642 -0.249642)
							(end 0.1778 -0.2794)
						)
					)
					(width 0)
					(fill yes)
				)
			)
		)
		(pad "2" smd custom
			(at 0 0.4445 180)
			(size 0.1397 0.1397)
			(layers "F.Cu" "F.Mask" "F.Paste")
			(net "SW_HDD4_R")
			(options
				(clearance outline)
				(anchor circle)
			)
			(primitives
				(gr_poly
					(pts
						(arc
							(start -0.1778 -0.2794)
							(mid -0.249642 -0.249642)
							(end -0.2794 -0.1778)
						)
						(arc
							(start -0.2794 0.1778)
							(mid -0.249642 0.249642)
							(end -0.1778 0.2794)
						)
						(arc
							(start 0.1778 0.2794)
							(mid 0.249642 0.249642)
							(end 0.2794 0.1778)
						)
						(arc
							(start 0.2794 -0.1778)
							(mid 0.249642 -0.249642)
							(end 0.1778 -0.2794)
						)
					)
					(width 0)
					(fill yes)
				)
			)
		)
	)
	(footprint ""
		(layer "F.Cu")
		(at 42.500042 -144.159986 180)
		(property "Reference" "LED9"
			(at 0 0 180)
			(layer "F.SilkS")
			(hide yes)
			(effects
				(font
					(size 1.27 1.27)
				)
			)
		)
		(property "Value" "LED-RB-4-GP"
			(at 5.88899 1.80848 180)
			(unlocked yes)
			(layer "F.Fab")
			(hide yes)
			(effects
				(font
					(size 1.016 1.016)
					(thickness 0.1524)
				)
			)
		)
		(property "Device Type" "LED1613-4PH20"
			(at 5.88899 0.28448 180)
			(unlocked yes)
			(layer "F.Fab")
			(hide yes)
			(effects
				(font
					(size 1.016 1.016)
					(thickness 0.1524)
				)
			)
		)
		(duplicate_pad_numbers_are_jumpers no)
		(fp_line
			(start 1.4478 0.9652)
			(end -1.4478 0.9652)
			(stroke
				(width 0.1524)
				(type default)
			)
			(layer "F.SilkS")
		)
		(fp_line
			(start 1.4478 -0.9652)
			(end 1.4478 0.9652)
			(stroke
				(width 0.1524)
				(type default)
			)
			(layer "F.SilkS")
		)
		(fp_line
			(start -1.4478 0.9652)
			(end -1.4478 -0.9652)
			(stroke
				(width 0.1524)
				(type default)
			)
			(layer "F.SilkS")
		)
		(fp_line
			(start -1.4478 0.9652)
			(end -1.4478 -0.9652)
			(stroke
				(width 0.508)
				(type default)
			)
			(layer "F.SilkS")
		)
		(fp_line
			(start -1.4478 -0.9652)
			(end 1.4478 -0.9652)
			(stroke
				(width 0.1524)
				(type default)
			)
			(layer "F.SilkS")
		)
		(fp_rect
			(start -0.8001 0.6477)
			(end 0.8001 -0.6477)
			(stroke
				(width 0)
				(type default)
			)
			(fill no)
			(layer "F.CrtYd")
		)
		(fp_poly
			(pts
				(xy -1.7018 1.2192) (xy -1.7018 -0.06223) (xy -0.8001 -0.06223) (xy -0.8001 0.6477) (xy 0.8001 0.6477)
				(xy 0.8001 -0.6477) (xy -0.8001 -0.6477) (xy -0.8001 -0.0635) (xy -1.7018 -0.0635) (xy -1.7018 -1.2192)
				(xy 1.7018 -1.2192) (xy 1.7018 1.2192)
			)
			(stroke
				(width 0)
				(type default)
			)
			(fill no)
			(layer "F.CrtYd")
		)
		(fp_rect
			(start -1.7018 1.2192)
			(end 1.7018 -1.2192)
			(stroke
				(width 0)
				(type default)
			)
			(fill no)
			(layer "F.Fab")
		)
		(pad "1" smd rect
			(at -0.73025 0.4064 180)
			(size 0.9144 0.6096)
			(layers "F.Cu" "F.Mask" "F.Paste")
			(net "DRV_ACT_NET8")
		)
		(pad "2" smd rect
			(at -0.73025 -0.4064 180)
			(size 0.9144 0.6096)
			(layers "F.Cu" "F.Mask" "F.Paste")
			(net "FLT_NET_HDD8")
		)
		(pad "3" smd rect
			(at 0.73025 -0.4064 180)
			(size 0.9144 0.6096)
			(layers "F.Cu" "F.Mask" "F.Paste")
			(net "FLT_HDD8")
		)
		(pad "4" smd rect
			(at 0.73025 0.4064 180)
			(size 0.9144 0.6096)
			(layers "F.Cu" "F.Mask" "F.Paste")
			(net "DRV_ACT_8")
		)
	)
)
